# S9S_MB_2U (Grand Teton) — schematic netlist excerpt (pin names and nets, part order shuffled) for the footprints in the layout excerpt that follows; sources: Cadence DE-HDL packaged netlist, KiCad conversion of 03242023_DA0F0TMBIJ0_F0T_Motherboard_J_brd_V01_OCP.brd

R276  Q_RES  240 1% EMPTY  pkg 0402LF  page 119 : A = PVNN_TERM_CPU0 ; B = PU_CPU0_SAFE_MODE_BOOT
R87  Q_RES  1K 1% EMPTY  pkg 0402LF  page 229 : A = P3V3_AUX ; B = FM_SPD_REMOTE_EN

(kicad_pcb
	(version 20260206)
	(generator "pcbnew")
	(generator_version "10.0")
	(general
		(thickness 1.6)
		(legacy_teardrops no)
	)
	(paper "A4")
	(title_block
		(title "03242023_DA0F0TMBIJ0_F0T_Motherboard_J_brd_V01_OCP.brd")
		(comment 1 "Grand Teton / footprints 4339-4340 of 6105")
	)
	(layers
		(0 "F.Cu" signal "TOP")
		(4 "In1.Cu" signal "GND")
		(6 "In2.Cu" signal "IN1")
		(8 "In3.Cu" signal "GND1")
		(10 "In4.Cu" signal "IN2")
		(12 "In5.Cu" signal "GND2")
		(14 "In6.Cu" signal "IN3")
		(16 "In7.Cu" signal "GND3")
		(18 "In8.Cu" signal "VCC")
		(20 "In9.Cu" signal "VCC1")
		(22 "In10.Cu" signal "GND4")
		(24 "In11.Cu" signal "IN4")
		(26 "In12.Cu" signal "GND5")
		(28 "In13.Cu" signal "IN5")
		(30 "In14.Cu" signal "GND6")
		(32 "In15.Cu" signal "IN6")
		(34 "In16.Cu" signal "GND7")
		(2 "B.Cu" signal "BOTTOM")
		(9 "F.Adhes" user "F.Adhesive")
		(11 "B.Adhes" user "B.Adhesive")
		(13 "F.Paste" user "Package Geometry/Pastemask Top")
		(15 "B.Paste" user "Package Geometry/Pastemask Bottom")
		(5 "F.SilkS" user "Ref Des/Silkscreen Top")
		(7 "B.SilkS" user "Ref Des/Silkscreen Bottom")
		(1 "F.Mask" user "Board Geometry/Soldermask Top")
		(3 "B.Mask" user "Board Geometry/Soldermask Bottom")
		(17 "Dwgs.User" user "User.Drawings")
		(19 "Cmts.User" user "User.Comments")
		(21 "Eco1.User" user "User.Eco1")
		(23 "Eco2.User" user "User.Eco2")
		(25 "Edge.Cuts" user "Board Geometry/Outline")
		(27 "Margin" user)
		(31 "F.CrtYd" user "Package Geometry/Place Bound Top")
		(29 "B.CrtYd" user "Package Geometry/Place Bound Bottom")
		(35 "F.Fab" user "Ref Des/Assembly Top")
		(33 "B.Fab" user "Ref Des/Assembly Bottom")
	)
	(footprint ""
		(layer "B.Cu")
		(at 312.13044 -193.74231 -90)
		(property "Reference" "R276"
			(at 0 0 90)
			(layer "B.SilkS")
			(hide yes)
			(effects
				(font
					(size 1.27 1.27)
				)
				(justify mirror)
			)
		)
		(property "Value" ""
			(at 0 0 90)
			(layer "B.Fab")
			(effects
				(font
					(size 1.27 1.27)
				)
				(justify mirror)
			)
		)
		(duplicate_pad_numbers_are_jumpers no)
		(fp_line
			(start -0.7874 0.4064)
			(end 0.7874 0.4064)
			(stroke
				(width 0.1524)
				(type default)
			)
			(layer "B.SilkS")
		)
		(fp_line
			(start 0.7874 0.4064)
			(end 0.7874 -0.4064)
			(stroke
				(width 0.1524)
				(type default)
			)
			(layer "B.SilkS")
		)
		(fp_line
			(start -0.7874 -0.4064)
			(end -0.7874 0.4064)
			(stroke
				(width 0.1524)
				(type default)
			)
			(layer "B.SilkS")
		)
		(fp_line
			(start 0.7874 -0.4064)
			(end -0.7874 -0.4064)
			(stroke
				(width 0.1524)
				(type default)
			)
			(layer "B.SilkS")
		)
		(fp_line
			(start -0.67945 0.3048)
			(end -0.120396 0.3048)
			(stroke
				(width 0.1)
				(type default)
			)
			(layer "B.Fab")
		)
		(fp_line
			(start -0.120396 0.3048)
			(end -0.120396 0.2794)
			(stroke
				(width 0.1)
				(type default)
			)
			(layer "B.Fab")
		)
		(fp_line
			(start 0.12065 0.3048)
			(end 0.67945 0.3048)
			(stroke
				(width 0.1)
				(type default)
			)
			(layer "B.Fab")
		)
		(fp_line
			(start 0.67945 0.3048)
			(end 0.67945 -0.305054)
			(stroke
				(width 0.1)
				(type default)
			)
			(layer "B.Fab")
		)
		(fp_line
			(start -0.120396 0.2794)
			(end 0.12065 0.2794)
			(stroke
				(width 0.1)
				(type default)
			)
			(layer "B.Fab")
		)
		(fp_line
			(start 0.12065 0.2794)
			(end 0.12065 0.3048)
			(stroke
				(width 0.1)
				(type default)
			)
			(layer "B.Fab")
		)
		(fp_line
			(start -0.12065 -0.2794)
			(end -0.12065 -0.3048)
			(stroke
				(width 0.1)
				(type default)
			)
			(layer "B.Fab")
		)
		(fp_line
			(start 0.12065 -0.2794)
			(end -0.12065 -0.2794)
			(stroke
				(width 0.1)
				(type default)
			)
			(layer "B.Fab")
		)
		(fp_line
			(start -0.67945 -0.3048)
			(end -0.67945 0.3048)
			(stroke
				(width 0.1)
				(type default)
			)
			(layer "B.Fab")
		)
		(fp_line
			(start -0.12065 -0.3048)
			(end -0.67945 -0.3048)
			(stroke
				(width 0.1)
				(type default)
			)
			(layer "B.Fab")
		)
		(fp_line
			(start 0.12065 -0.305054)
			(end 0.12065 -0.2794)
			(stroke
				(width 0.1)
				(type default)
			)
			(layer "B.Fab")
		)
		(fp_line
			(start 0.67945 -0.305054)
			(end 0.12065 -0.305054)
			(stroke
				(width 0.1)
				(type default)
			)
			(layer "B.Fab")
		)
		(pad "1" smd circle
			(at 0.40005 0 90)
			(size 0 0)
			(layers "B.Cu" "B.Mask" "B.Paste")
			(net "PVNN_TERM_CPU0")
		)
		(pad "2" smd circle
			(at -0.40005 0 90)
			(size 0 0)
			(layers "B.Cu" "B.Mask" "B.Paste")
			(net "PU_CPU0_SAFE_MODE_BOOT")
		)
	)
	(footprint ""
		(layer "B.Cu")
		(at 291.964618 -149.992588 -90)
		(property "Reference" "R87"
			(at 0 0 90)
			(layer "B.SilkS")
			(hide yes)
			(effects
				(font
					(size 1.27 1.27)
				)
				(justify mirror)
			)
		)
		(property "Value" ""
			(at 0 0 90)
			(layer "B.Fab")
			(effects
				(font
					(size 1.27 1.27)
				)
				(justify mirror)
			)
		)
		(duplicate_pad_numbers_are_jumpers no)
		(fp_line
			(start -0.7874 0.4064)
			(end 0.7874 0.4064)
			(stroke
				(width 0.1524)
				(type default)
			)
			(layer "B.SilkS")
		)
		(fp_line
			(start 0.7874 0.4064)
			(end 0.7874 -0.4064)
			(stroke
				(width 0.1524)
				(type default)
			)
			(layer "B.SilkS")
		)
		(fp_line
			(start -0.7874 -0.4064)
			(end -0.7874 0.4064)
			(stroke
				(width 0.1524)
				(type default)
			)
			(layer "B.SilkS")
		)
		(fp_line
			(start 0.7874 -0.4064)
			(end -0.7874 -0.4064)
			(stroke
				(width 0.1524)
				(type default)
			)
			(layer "B.SilkS")
		)
		(fp_line
			(start -0.67945 0.3048)
			(end -0.120396 0.3048)
			(stroke
				(width 0.1)
				(type default)
			)
			(layer "B.Fab")
		)
		(fp_line
			(start -0.120396 0.3048)
			(end -0.120396 0.2794)
			(stroke
				(width 0.1)
				(type default)
			)
			(layer "B.Fab")
		)
		(fp_line
			(start 0.12065 0.3048)
			(end 0.67945 0.3048)
			(stroke
				(width 0.1)
				(type default)
			)
			(layer "B.Fab")
		)
		(fp_line
			(start 0.67945 0.3048)
			(end 0.67945 -0.305054)
			(stroke
				(width 0.1)
				(type default)
			)
			(layer "B.Fab")
		)
		(fp_line
			(start -0.120396 0.2794)
			(end 0.12065 0.2794)
			(stroke
				(width 0.1)
				(type default)
			)
			(layer "B.Fab")
		)
		(fp_line
			(start 0.12065 0.2794)
			(end 0.12065 0.3048)
			(stroke
				(width 0.1)
				(type default)
			)
			(layer "B.Fab")
		)
		(fp_line
			(start -0.12065 -0.2794)
			(end -0.12065 -0.3048)
			(stroke
				(width 0.1)
				(type default)
			)
			(layer "B.Fab")
		)
		(fp_line
			(start 0.12065 -0.2794)
			(end -0.12065 -0.2794)
			(stroke
				(width 0.1)
				(type default)
			)
			(layer "B.Fab")
		)
		(fp_line
			(start -0.67945 -0.3048)
			(end -0.67945 0.3048)
			(stroke
				(width 0.1)
				(type default)
			)
			(layer "B.Fab")
		)
		(fp_line
			(start -0.12065 -0.3048)
			(end -0.67945 -0.3048)
			(stroke
				(width 0.1)
				(type default)
			)
			(layer "B.Fab")
		)
		(fp_line
			(start 0.12065 -0.305054)
			(end 0.12065 -0.2794)
			(stroke
				(width 0.1)
				(type default)
			)
			(layer "B.Fab")
		)
		(fp_line
			(start 0.67945 -0.305054)
			(end 0.12065 -0.305054)
			(stroke
				(width 0.1)
				(type default)
			)
			(layer "B.Fab")
		)
		(pad "1" smd circle
			(at 0.40005 0 90)
			(size 0 0)
			(layers "B.Cu" "B.Mask" "B.Paste")
			(net "P3V3_AUX")
		)
		(pad "2" smd circle
			(at -0.40005 0 90)
			(size 0 0)
			(layers "B.Cu" "B.Mask" "B.Paste")
			(net "FM_SPD_REMOTE_EN")
		)
	)
)
